# BASEBOARD_FAB2 (Tioga Pass) — schematic netlist excerpt (pin names and nets, part order shuffled) for the footprints in the layout excerpt that follows; sources: Cadence DE-HDL packaged netlist, KiCad conversion of Wiwynn_Tioga_Pass_MB.brd

J9M1  SCONN288_H44441003  SCONN  pkg PIP  page 84
  \12v\(1)  = P12V_NVDIMM_KLM
  VSS(93)  = GND
  DQ(4)  = M_K_DQ<4>
  VSS(92)  = GND
  DQ(0)  = M_K_DQ<0>
  VSS(91)  = GND
  DQS9P  = M_K_DQS_DP<9>
  DQS9N  = M_K_DQS_DN<9>
  VSS(90)  = GND
  DQ(6)  = M_K_DQ<6>
  VSS(89)  = GND
  DQ(2)  = M_K_DQ<2>
  VSS(88)  = GND
  DQ(12)  = M_K_DQ<12>
  VSS(87)  = GND
  DQ(8)  = M_K_DQ<8>
  VSS(86)  = GND
  DQS10P  = M_K_DQS_DP<10>
  DQS10N  = M_K_DQS_DN<10>
  VSS(85)  = GND
  DQ(14)  = M_K_DQ<14>
  VSS(84)  = GND
  DQ(10)  = M_K_DQ<10>
  VSS(83)  = GND
  DQ(20)  = M_K_DQ<20>
  VSS(82)  = GND
  DQ(16)  = M_K_DQ<16>
  VSS(81)  = GND
  DQS11P  = M_K_DQS_DP<11>
  DQS11N  = M_K_DQS_DN<11>
  VSS(80)  = GND
  DQ(22)  = M_K_DQ<22>
  VSS(79)  = GND
  DQ(18)  = M_K_DQ<18>
  VSS(78)  = GND
  DQ(28)  = M_K_DQ<28>
  VSS(77)  = GND
  DQ(24)  = M_K_DQ<24>
  VSS(76)  = GND
  DQS12P  = M_K_DQS_DP<12>
  DQS12N  = M_K_DQS_DN<12>
  VSS(75)  = GND
  DQ(30)  = M_K_DQ<30>
  VSS(74)  = GND
  DQ(26)  = M_K_DQ<26>
  VSS(73)  = GND
  CB(4)  = M_K_ECC<4>
  VSS(72)  = GND
  CB(0)  = M_K_ECC<0>
  VSS(71)  = GND
  DQS17P  = M_K_DQS_DP<17>
  DQS17N  = M_K_DQS_DN<17>
  VSS(70)  = GND
  CB(6)  = M_K_ECC<6>
  VSS(69)  = GND
  CB(2)  = M_K_ECC<2>
  VSS(68)  = GND
  RESET_N  = M_KLM_RST_N
  VDD(25)  = PVDDQ_KLM
  CKE(0)  = M_K_CKE<2>
  VDD(24)  = PVDDQ_KLM
  ACT_N  = M_K_ACT_N
  BG(0)  = M_K_BG<0>
  VDD(23)  = PVDDQ_KLM
  A12  = M_K_MA<12>
  A9  = M_K_MA<9>
  VDD(22)  = PVDDQ_KLM
  A8  = M_K_MA<8>
  A6  = M_K_MA<6>
  VDD(21)  = PVDDQ_KLM
  A3  = M_K_MA<3>
  A1  = M_K_MA<1>
  VDD(20)  = PVDDQ_KLM
  CK0P  = M_K_CLK_DP<2>
  CK0N  = M_K_CLK_DN<2>
  VDD(19)  = PVDDQ_KLM
  VTT(1)  = PVTT_KLM
  EVENT_N  = FM_DIMM_EVENT_COD_N
  A0  = M_K_MA<0>
  VDD(18)  = PVDDQ_KLM
  BA(0)  = M_K_BA<0>
  A16_RAS_N  = M_K_MA<16>
  VDD(17)  = PVDDQ_KLM
  S0_N  = M_K_CS_N<4>
  VDD(16)  = PVDDQ_KLM
  A15_CAS_N  = M_K_MA<15>
  ODT(0)  = M_K_ODT<2>
  VDD(15)  = PVDDQ_KLM
  S1_N  = M_K_CS_N<5>
  VDD(14)  = PVDDQ_KLM
  ODT(1)  = M_K_ODT<3>
  VDD(13)  = PVDDQ_KLM
  S2_N_C(0)  = M_K_CS_N<6>
  VSS(67)  = GND
  DQ(36)  = M_K_DQ<36>
  VSS(66)  = GND
  DQ(32)  = M_K_DQ<32>
  VSS(65)  = GND
  DQS13P  = M_K_DQS_DP<13>
  DQS13N  = M_K_DQS_DN<13>
  VSS(64)  = GND
  DQ(38)  = M_K_DQ<38>
  VSS(63)  = GND
  DQ(34)  = M_K_DQ<34>
  VSS(62)  = GND
  DQ(44)  = M_K_DQ<44>
  VSS(61)  = GND
  DQ(40)  = M_K_DQ<40>
  VSS(60)  = GND
  DQS14P  = M_K_DQS_DP<14>
  DQS14N  = M_K_DQS_DN<14>
  VSS(59)  = GND
  DQ(46)  = M_K_DQ<46>
  VSS(58)  = GND
  DQ(42)  = M_K_DQ<42>
  VSS(57)  = GND
  DQ(52)  = M_K_DQ<52>
  VSS(56)  = GND
  DQ(48)  = M_K_DQ<48>
  VSS(55)  = GND
  DQS15P  = M_K_DQS_DP<15>
  DQS15N  = M_K_DQS_DN<15>
  VSS(54)  = GND
  DQ(54)  = M_K_DQ<54>
  VSS(53)  = GND
  DQ(50)  = M_K_DQ<50>
  VSS(52)  = GND
  DQ(60)  = M_K_DQ<60>
  VSS(51)  = GND
  DQ(56)  = M_K_DQ<56>
  VSS(50)  = GND
  DQS16P  = M_K_DQS_DP<16>
  DQS16N  = M_K_DQS_DN<16>
  VSS(49)  = GND
  DQ(62)  = M_K_DQ<62>
  VSS(48)  = GND
  DQ(58)  = M_K_DQ<58>
  VSS(47)  = GND
  SA(0)  = PVPP_KLM
  SA(1)  = GND
  SCL  = SMB_DDR_KLM_VPP_SCL
  VPP(4)  = PVPP_KLM
  VPP(3)  = PVPP_KLM
  RFU(2)  = TP_CH_K_DIMM0_RFU_2
  \12v\(0)  = P12V_NVDIMM_KLM
  VREFCA  = M_K_VREF
  VSS(46)  = GND
  DQ(5)  = M_K_DQ<5>
  VSS(45)  = GND
  DQ(1)  = M_K_DQ<1>
  VSS(44)  = GND
  DQS0N  = M_K_DQS_DN<0>
  DQS0P  = M_K_DQS_DP<0>
  VSS(43)  = GND
  DQ(7)  = M_K_DQ<7>
  VSS(42)  = GND
  DQ(3)  = M_K_DQ<3>
  VSS(41)  = GND
  DQ(13)  = M_K_DQ<13>
  VSS(40)  = GND
  DQ(9)  = M_K_DQ<9>
  VSS(39)  = GND
  DQS1N  = M_K_DQS_DN<1>
  DQS1P  = M_K_DQS_DP<1>
  VSS(38)  = GND
  DQ(15)  = M_K_DQ<15>
  VSS(37)  = GND
  DQ(11)  = M_K_DQ<11>
  VSS(36)  = GND
  DQ(21)  = M_K_DQ<21>
  VSS(35)  = GND
  DQ(17)  = M_K_DQ<17>
  VSS(34)  = GND
  DQS2N  = M_K_DQS_DN<2>
  DQS2P  = M_K_DQS_DP<2>
  VSS(33)  = GND
  DQ(23)  = M_K_DQ<23>
  VSS(32)  = GND
  DQ(19)  = M_K_DQ<19>
  VSS(31)  = GND
  DQ(29)  = M_K_DQ<29>
  VSS(30)  = GND
  DQ(25)  = M_K_DQ<25>
  VSS(29)  = GND
  DQS3N  = M_K_DQS_DN<3>
  DQS3P  = M_K_DQS_DP<3>
  VSS(28)  = GND
  DQ(31)  = M_K_DQ<31>
  VSS(27)  = GND
  DQ(27)  = M_K_DQ<27>
  VSS(26)  = GND
  CB(5)  = M_K_ECC<5>
  VSS(25)  = GND
  CB(1)  = M_K_ECC<1>
  VSS(24)  = GND
  DQS8N  = M_K_DQS_DN<8>
  DQS8P  = M_K_DQS_DP<8>
  VSS(23)  = GND
  CB(7)  = M_K_ECC<7>
  VSS(22)  = GND
  CB(3)  = M_K_ECC<3>
  VSS(21)  = GND
  CKE(1)  = M_K_CKE<3>
  VDD(12)  = PVDDQ_KLM
  RFU(0)  = TP_CH_K_DIMM0_RFU_0
  VDD(11)  = PVDDQ_KLM
  BG(1)  = M_K_BG<1>
  ALERT_N  = M_K_ALERT_N
  VDD(10)  = PVDDQ_KLM
  A11  = M_K_MA<11>
  A7  = M_K_MA<7>
  VDD(9)  = PVDDQ_KLM
  A5  = M_K_MA<5>
  A4  = M_K_MA<4>
  VDD(8)  = PVDDQ_KLM
  A2  = M_K_MA<2>
  VDD(7)  = PVDDQ_KLM
  CK1P  = M_K_CLK_DP<3>
  CK1N  = M_K_CLK_DN<3>
  VDD(6)  = PVDDQ_KLM
  VTT(0)  = PVTT_KLM
  PAR  = M_K_PAR
  VDD(5)  = PVDDQ_KLM
  BA(1)  = M_K_BA<1>
  A10  = M_K_MA<10>
  VDD(4)  = PVDDQ_KLM
  RFU(1)  = TP_CH_K_DIMM0_RFU_1
  A14_WE_N  = M_K_MA<14>
  VDD(3)  = PVDDQ_KLM
  SAVE_N_NC  = FM_ADR_COMPLETE_KLM_N
  VDD(2)  = PVDDQ_KLM
  A13  = M_K_MA<13>
  VDD(1)  = PVDDQ_KLM
  A17  = M_K_MA<17>
  C(2)  = M_K_C<2>
  VDD(0)  = PVDDQ_KLM
  S3_N_C(1)  = M_K_CS_N<7>
  SA(2)  = GND
  VSS(20)  = GND
  DQ(37)  = M_K_DQ<37>
  VSS(19)  = GND
  DQ(33)  = M_K_DQ<33>
  VSS(18)  = GND
  DQS4N  = M_K_DQS_DN<4>
  DQS4P  = M_K_DQS_DP<4>
  VSS(17)  = GND
  DQ(39)  = M_K_DQ<39>
  VSS(16)  = GND
  DQ(35)  = M_K_DQ<35>
  VSS(15)  = GND
  DQ(45)  = M_K_DQ<45>
  VSS(14)  = GND
  DQ(41)  = M_K_DQ<41>
  VSS(13)  = GND
  DQS5N  = M_K_DQS_DN<5>
  DQS5P  = M_K_DQS_DP<5>
  VSS(12)  = GND
  DQ(47)  = M_K_DQ<47>
  VSS(11)  = GND
  DQ(43)  = M_K_DQ<43>
  VSS(10)  = GND
  DQ(53)  = M_K_DQ<53>
  VSS(9)  = GND
  DQ(49)  = M_K_DQ<49>
  VSS(8)  = GND
  DQS6N  = M_K_DQS_DN<6>
  DQS6P  = M_K_DQS_DP<6>
  VSS(7)  = GND
  DQ(55)  = M_K_DQ<55>
  VSS(6)  = GND
  DQ(51)  = M_K_DQ<51>
  VSS(5)  = GND
  DQ(61)  = M_K_DQ<61>
  VSS(4)  = GND
  DQ(57)  = M_K_DQ<57>
  VSS(3)  = GND
  DQS7N  = M_K_DQS_DN<7>
  DQS7P  = M_K_DQS_DP<7>
  VSS(2)  = GND
  DQ(63)  = M_K_DQ<63>
  VSS(1)  = GND
  DQ(59)  = M_K_DQ<59>
  VSS(0)  = GND
  VDDSPD  = PVPP_KLM
  SDA  = SMB_DDR_KLM_VPP_SDA
  VPP(1)  = PVPP_KLM
  VPP(0)  = PVPP_KLM
  VPP(2)  = PVPP_KLM

(kicad_pcb
	(version 20260206)
	(generator "pcbnew")
	(generator_version "10.0")
	(general
		(thickness 1.6)
		(legacy_teardrops no)
	)
	(paper "A4")
	(title_block
		(title "Wiwynn_Tioga_Pass_MB.brd")
		(comment 1 "Tioga Pass / footprint 2445 of 4770 (J9M1), pads 152-201 of 291")
	)
	(layers
		(0 "F.Cu" signal "TOP")
		(4 "In1.Cu" signal "L2GND")
		(6 "In2.Cu" signal "L3")
		(8 "In3.Cu" signal "L4GND")
		(10 "In4.Cu" signal "L5")
		(12 "In5.Cu" signal "L6GND")
		(14 "In6.Cu" signal "L7VCC")
		(16 "In7.Cu" signal "L8VCC")
		(18 "In8.Cu" signal "L9GND")
		(20 "In9.Cu" signal "L10")
		(22 "In10.Cu" signal "L11GND")
		(24 "In11.Cu" signal "L12")
		(26 "In12.Cu" signal "L13GND")
		(2 "B.Cu" signal "BOTTOM")
		(9 "F.Adhes" user "F.Adhesive")
		(11 "B.Adhes" user "B.Adhesive")
		(13 "F.Paste" user "Package Geometry/Pastemask Top")
		(15 "B.Paste" user "Package Geometry/Pastemask Bottom")
		(5 "F.SilkS" user "Ref Des/Silkscreen Top")
		(7 "B.SilkS" user "Ref Des/Silkscreen Bottom")
		(1 "F.Mask" user "Board Geometry/Soldermask Top")
		(3 "B.Mask" user "Board Geometry/Soldermask Bottom")
		(17 "Dwgs.User" user "User.Drawings")
		(19 "Cmts.User" user "User.Comments")
		(21 "Eco1.User" user "User.Eco1")
		(23 "Eco2.User" user "User.Eco2")
		(25 "Edge.Cuts" user "Board Geometry/Outline")
		(27 "Margin" user)
		(31 "F.CrtYd" user "Package Geometry/Place Bound Top")
		(29 "B.CrtYd" user "Package Geometry/Place Bound Bottom")
		(35 "F.Fab" user "Ref Des/Assembly Top")
		(33 "B.Fab" user "Ref Des/Assembly Bottom")
	)
	(footprint ""
		(layer "B.Cu")
		(at 29.699458 -132.876036 90)
		(property "Reference" "J9M1"
			(at 2.352548 37.991542 0)
			(unlocked yes)
			(layer "B.SilkS")
			(effects
				(font
					(size 0.7874 0.5842)
					(thickness 0.1524)
				)
				(justify left mirror)
			)
		)
		(property "Value" ""
			(at 0 0 90)
			(layer "B.Fab")
			(effects
				(font
					(size 1.27 1.27)
				)
				(justify mirror)
			)
		)
		(duplicate_pad_numbers_are_jumpers no)
		(pad "149" smd rect
			(at -4.59994 3.400044 270)
			(size 1.8034 0.508)
			(layers "B.Cu" "B.Mask" "B.Paste")
			(net "GND")
		)
		(pad "150" smd rect
			(at -4.59994 4.249928 270)
			(size 1.8034 0.508)
			(layers "B.Cu" "B.Mask" "B.Paste")
			(net "M_K_DQ<1>")
		)
		(pad "151" smd rect
			(at -4.59994 5.100066 270)
			(size 1.8034 0.508)
			(layers "B.Cu" "B.Mask" "B.Paste")
			(net "GND")
		)
		(pad "152" smd rect
			(at -4.59994 5.94995 270)
			(size 1.8034 0.508)
			(layers "B.Cu" "B.Mask" "B.Paste")
			(net "M_K_DQS_DN<0>")
		)
		(pad "153" smd rect
			(at -4.59994 6.800088 270)
			(size 1.8034 0.508)
			(layers "B.Cu" "B.Mask" "B.Paste")
			(net "M_K_DQS_DP<0>")
		)
		(pad "154" smd rect
			(at -4.59994 7.649972 270)
			(size 1.8034 0.508)
			(layers "B.Cu" "B.Mask" "B.Paste")
			(net "GND")
		)
		(pad "155" smd rect
			(at -4.59994 8.50011 270)
			(size 1.8034 0.508)
			(layers "B.Cu" "B.Mask" "B.Paste")
			(net "M_K_DQ<7>")
		)
		(pad "156" smd rect
			(at -4.59994 9.349994 270)
			(size 1.8034 0.508)
			(layers "B.Cu" "B.Mask" "B.Paste")
			(net "GND")
		)
		(pad "157" smd rect
			(at -4.59994 10.199878 270)
			(size 1.8034 0.508)
			(layers "B.Cu" "B.Mask" "B.Paste")
			(net "M_K_DQ<3>")
		)
		(pad "158" smd rect
			(at -4.59994 11.050016 270)
			(size 1.8034 0.508)
			(layers "B.Cu" "B.Mask" "B.Paste")
			(net "GND")
		)
		(pad "159" smd rect
			(at -4.59994 11.8999 270)
			(size 1.8034 0.508)
			(layers "B.Cu" "B.Mask" "B.Paste")
			(net "M_K_DQ<13>")
		)
		(pad "160" smd rect
			(at -4.59994 12.750038 270)
			(size 1.8034 0.508)
			(layers "B.Cu" "B.Mask" "B.Paste")
			(net "GND")
		)
		(pad "161" smd rect
			(at -4.59994 13.599922 270)
			(size 1.8034 0.508)
			(layers "B.Cu" "B.Mask" "B.Paste")
			(net "M_K_DQ<9>")
		)
		(pad "162" smd rect
			(at -4.59994 14.45006 270)
			(size 1.8034 0.508)
			(layers "B.Cu" "B.Mask" "B.Paste")
			(net "GND")
		)
		(pad "163" smd rect
			(at -4.59994 15.299944 270)
			(size 1.8034 0.508)
			(layers "B.Cu" "B.Mask" "B.Paste")
			(net "M_K_DQS_DN<1>")
		)
		(pad "164" smd rect
			(at -4.59994 16.150082 270)
			(size 1.8034 0.508)
			(layers "B.Cu" "B.Mask" "B.Paste")
			(net "M_K_DQS_DP<1>")
		)
		(pad "165" smd rect
			(at -4.59994 16.999966 270)
			(size 1.8034 0.508)
			(layers "B.Cu" "B.Mask" "B.Paste")
			(net "GND")
		)
		(pad "166" smd rect
			(at -4.59994 17.850104 270)
			(size 1.8034 0.508)
			(layers "B.Cu" "B.Mask" "B.Paste")
			(net "M_K_DQ<15>")
		)
		(pad "167" smd rect
			(at -4.59994 18.699988 270)
			(size 1.8034 0.508)
			(layers "B.Cu" "B.Mask" "B.Paste")
			(net "GND")
		)
		(pad "168" smd rect
			(at -4.59994 19.550126 270)
			(size 1.8034 0.508)
			(layers "B.Cu" "B.Mask" "B.Paste")
			(net "M_K_DQ<11>")
		)
		(pad "169" smd rect
			(at -4.59994 20.40001 270)
			(size 1.8034 0.508)
			(layers "B.Cu" "B.Mask" "B.Paste")
			(net "GND")
		)
		(pad "170" smd rect
			(at -4.59994 21.249894 270)
			(size 1.8034 0.508)
			(layers "B.Cu" "B.Mask" "B.Paste")
			(net "M_K_DQ<21>")
		)
		(pad "171" smd rect
			(at -4.59994 22.100032 270)
			(size 1.8034 0.508)
			(layers "B.Cu" "B.Mask" "B.Paste")
			(net "GND")
		)
		(pad "172" smd rect
			(at -4.59994 22.949916 270)
			(size 1.8034 0.508)
			(layers "B.Cu" "B.Mask" "B.Paste")
			(net "M_K_DQ<17>")
		)
		(pad "173" smd rect
			(at -4.59994 23.800054 270)
			(size 1.8034 0.508)
			(layers "B.Cu" "B.Mask" "B.Paste")
			(net "GND")
		)
		(pad "174" smd rect
			(at -4.59994 24.649938 270)
			(size 1.8034 0.508)
			(layers "B.Cu" "B.Mask" "B.Paste")
			(net "M_K_DQS_DN<2>")
		)
		(pad "175" smd rect
			(at -4.59994 25.500076 270)
			(size 1.8034 0.508)
			(layers "B.Cu" "B.Mask" "B.Paste")
			(net "M_K_DQS_DP<2>")
		)
		(pad "176" smd rect
			(at -4.59994 26.34996 270)
			(size 1.8034 0.508)
			(layers "B.Cu" "B.Mask" "B.Paste")
			(net "GND")
		)
		(pad "177" smd rect
			(at -4.59994 27.200098 270)
			(size 1.8034 0.508)
			(layers "B.Cu" "B.Mask" "B.Paste")
			(net "M_K_DQ<23>")
		)
		(pad "178" smd rect
			(at -4.59994 28.049982 270)
			(size 1.8034 0.508)
			(layers "B.Cu" "B.Mask" "B.Paste")
			(net "GND")
		)
		(pad "179" smd rect
			(at -4.59994 28.90012 270)
			(size 1.8034 0.508)
			(layers "B.Cu" "B.Mask" "B.Paste")
			(net "M_K_DQ<19>")
		)
		(pad "180" smd rect
			(at -4.59994 29.750004 270)
			(size 1.8034 0.508)
			(layers "B.Cu" "B.Mask" "B.Paste")
			(net "GND")
		)
		(pad "181" smd rect
			(at -4.59994 30.599888 270)
			(size 1.8034 0.508)
			(layers "B.Cu" "B.Mask" "B.Paste")
			(net "M_K_DQ<29>")
		)
		(pad "182" smd rect
			(at -4.59994 31.450026 270)
			(size 1.8034 0.508)
			(layers "B.Cu" "B.Mask" "B.Paste")
			(net "GND")
		)
		(pad "183" smd rect
			(at -4.59994 32.29991 270)
			(size 1.8034 0.508)
			(layers "B.Cu" "B.Mask" "B.Paste")
			(net "M_K_DQ<25>")
		)
		(pad "184" smd rect
			(at -4.59994 33.150048 270)
			(size 1.8034 0.508)
			(layers "B.Cu" "B.Mask" "B.Paste")
			(net "GND")
		)
		(pad "185" smd rect
			(at -4.59994 33.999932 270)
			(size 1.8034 0.508)
			(layers "B.Cu" "B.Mask" "B.Paste")
			(net "M_K_DQS_DN<3>")
		)
		(pad "186" smd rect
			(at -4.59994 34.85007 270)
			(size 1.8034 0.508)
			(layers "B.Cu" "B.Mask" "B.Paste")
			(net "M_K_DQS_DP<3>")
		)
		(pad "187" smd rect
			(at -4.59994 35.699954 270)
			(size 1.8034 0.508)
			(layers "B.Cu" "B.Mask" "B.Paste")
			(net "GND")
		)
		(pad "188" smd rect
			(at -4.59994 36.550092 270)
			(size 1.8034 0.508)
			(layers "B.Cu" "B.Mask" "B.Paste")
			(net "M_K_DQ<31>")
		)
		(pad "189" smd rect
			(at -4.59994 37.399976 270)
			(size 1.8034 0.508)
			(layers "B.Cu" "B.Mask" "B.Paste")
			(net "GND")
		)
		(pad "190" smd rect
			(at -4.59994 38.250114 270)
			(size 1.8034 0.508)
			(layers "B.Cu" "B.Mask" "B.Paste")
			(net "M_K_DQ<27>")
		)
		(pad "191" smd rect
			(at -4.59994 39.099998 270)
			(size 1.8034 0.508)
			(layers "B.Cu" "B.Mask" "B.Paste")
			(net "GND")
		)
		(pad "192" smd rect
			(at -4.59994 39.949882 270)
			(size 1.8034 0.508)
			(layers "B.Cu" "B.Mask" "B.Paste")
			(net "M_K_ECC<5>")
		)
		(pad "193" smd rect
			(at -4.59994 40.80002 270)
			(size 1.8034 0.508)
			(layers "B.Cu" "B.Mask" "B.Paste")
			(net "GND")
		)
		(pad "194" smd rect
			(at -4.59994 41.649904 270)
			(size 1.8034 0.508)
			(layers "B.Cu" "B.Mask" "B.Paste")
			(net "M_K_ECC<1>")
		)
		(pad "195" smd rect
			(at -4.59994 42.500042 270)
			(size 1.8034 0.508)
			(layers "B.Cu" "B.Mask" "B.Paste")
			(net "GND")
		)
		(pad "196" smd rect
			(at -4.59994 43.349926 270)
			(size 1.8034 0.508)
			(layers "B.Cu" "B.Mask" "B.Paste")
			(net "M_K_DQS_DN<8>")
		)
		(pad "197" smd rect
			(at -4.59994 44.200064 270)
			(size 1.8034 0.508)
			(layers "B.Cu" "B.Mask" "B.Paste")
			(net "M_K_DQS_DP<8>")
		)
		(pad "198" smd rect
			(at -4.59994 45.049948 270)
			(size 1.8034 0.508)
			(layers "B.Cu" "B.Mask" "B.Paste")
			(net "GND")
		)
	)
)
